# S9S_MB_2U (Grand Teton) — schematic netlist excerpt (pin names and nets, part order shuffled) for the footprints in the layout excerpt that follows; sources: Cadence DE-HDL packaged netlist, KiCad conversion of 03242023_DA0F0TMBIJ0_F0T_Motherboard_J_brd_V01_OCP.brd

C304  Q_CAP  22UF 4V 20% X6S  pkg C0402  page 77 : A = PVCCIN_CPU1 ; B = GND
R3440  Q_RES  0 5% EMPTY  pkg 0402LF  page 144 : A = GPU_BASE_ID0 ; B = GND

(kicad_pcb
	(version 20260206)
	(generator "pcbnew")
	(generator_version "10.0")
	(general
		(thickness 1.6)
		(legacy_teardrops no)
	)
	(paper "A4")
	(title_block
		(title "03242023_DA0F0TMBIJ0_F0T_Motherboard_J_brd_V01_OCP.brd")
		(comment 1 "Grand Teton / footprints 1783-1784 of 6105")
	)
	(layers
		(0 "F.Cu" signal "TOP")
		(4 "In1.Cu" signal "GND")
		(6 "In2.Cu" signal "IN1")
		(8 "In3.Cu" signal "GND1")
		(10 "In4.Cu" signal "IN2")
		(12 "In5.Cu" signal "GND2")
		(14 "In6.Cu" signal "IN3")
		(16 "In7.Cu" signal "GND3")
		(18 "In8.Cu" signal "VCC")
		(20 "In9.Cu" signal "VCC1")
		(22 "In10.Cu" signal "GND4")
		(24 "In11.Cu" signal "IN4")
		(26 "In12.Cu" signal "GND5")
		(28 "In13.Cu" signal "IN5")
		(30 "In14.Cu" signal "GND6")
		(32 "In15.Cu" signal "IN6")
		(34 "In16.Cu" signal "GND7")
		(2 "B.Cu" signal "BOTTOM")
		(9 "F.Adhes" user "F.Adhesive")
		(11 "B.Adhes" user "B.Adhesive")
		(13 "F.Paste" user "Package Geometry/Pastemask Top")
		(15 "B.Paste" user "Package Geometry/Pastemask Bottom")
		(5 "F.SilkS" user "Ref Des/Silkscreen Top")
		(7 "B.SilkS" user "Ref Des/Silkscreen Bottom")
		(1 "F.Mask" user "Board Geometry/Soldermask Top")
		(3 "B.Mask" user "Board Geometry/Soldermask Bottom")
		(17 "Dwgs.User" user "User.Drawings")
		(19 "Cmts.User" user "User.Comments")
		(21 "Eco1.User" user "User.Eco1")
		(23 "Eco2.User" user "User.Eco2")
		(25 "Edge.Cuts" user "Board Geometry/Outline")
		(27 "Margin" user)
		(31 "F.CrtYd" user "Package Geometry/Place Bound Top")
		(29 "B.CrtYd" user "Package Geometry/Place Bound Bottom")
		(35 "F.Fab" user "Ref Des/Assembly Top")
		(33 "B.Fab" user "Ref Des/Assembly Bottom")
	)
	(footprint ""
		(layer "F.Cu")
		(at 107.28833 -238.162592 -90)
		(property "Reference" "C304"
			(at 0 0 270)
			(layer "F.SilkS")
			(hide yes)
			(effects
				(font
					(size 1.27 1.27)
				)
			)
		)
		(property "Value" ""
			(at 0 0 270)
			(layer "F.Fab")
			(effects
				(font
					(size 1.27 1.27)
				)
			)
		)
		(duplicate_pad_numbers_are_jumpers no)
		(fp_line
			(start -0.7874 0.4064)
			(end -0.7874 -0.4064)
			(stroke
				(width 0.1524)
				(type default)
			)
			(layer "F.SilkS")
		)
		(fp_line
			(start 0.7874 0.4064)
			(end -0.7874 0.4064)
			(stroke
				(width 0.1524)
				(type default)
			)
			(layer "F.SilkS")
		)
		(fp_line
			(start -0.7874 -0.4064)
			(end 0.7874 -0.4064)
			(stroke
				(width 0.1524)
				(type default)
			)
			(layer "F.SilkS")
		)
		(fp_line
			(start 0.7874 -0.4064)
			(end 0.7874 0.4064)
			(stroke
				(width 0.1524)
				(type default)
			)
			(layer "F.SilkS")
		)
		(fp_line
			(start -0.67945 0.3048)
			(end -0.67945 -0.305054)
			(stroke
				(width 0.1)
				(type default)
			)
			(layer "F.Fab")
		)
		(fp_line
			(start -0.12065 0.3048)
			(end -0.67945 0.3048)
			(stroke
				(width 0.1)
				(type default)
			)
			(layer "F.Fab")
		)
		(fp_line
			(start 0.120396 0.3048)
			(end 0.120396 0.2794)
			(stroke
				(width 0.1)
				(type default)
			)
			(layer "F.Fab")
		)
		(fp_line
			(start 0.67945 0.3048)
			(end 0.120396 0.3048)
			(stroke
				(width 0.1)
				(type default)
			)
			(layer "F.Fab")
		)
		(fp_line
			(start -0.12065 0.2794)
			(end -0.12065 0.3048)
			(stroke
				(width 0.1)
				(type default)
			)
			(layer "F.Fab")
		)
		(fp_line
			(start 0.120396 0.2794)
			(end -0.12065 0.2794)
			(stroke
				(width 0.1)
				(type default)
			)
			(layer "F.Fab")
		)
		(fp_line
			(start -0.12065 -0.2794)
			(end 0.12065 -0.2794)
			(stroke
				(width 0.1)
				(type default)
			)
			(layer "F.Fab")
		)
		(fp_line
			(start 0.12065 -0.2794)
			(end 0.12065 -0.3048)
			(stroke
				(width 0.1)
				(type default)
			)
			(layer "F.Fab")
		)
		(fp_line
			(start 0.12065 -0.3048)
			(end 0.67945 -0.3048)
			(stroke
				(width 0.1)
				(type default)
			)
			(layer "F.Fab")
		)
		(fp_line
			(start 0.67945 -0.3048)
			(end 0.67945 0.3048)
			(stroke
				(width 0.1)
				(type default)
			)
			(layer "F.Fab")
		)
		(fp_line
			(start -0.67945 -0.305054)
			(end -0.12065 -0.305054)
			(stroke
				(width 0.1)
				(type default)
			)
			(layer "F.Fab")
		)
		(fp_line
			(start -0.12065 -0.305054)
			(end -0.12065 -0.2794)
			(stroke
				(width 0.1)
				(type default)
			)
			(layer "F.Fab")
		)
		(pad "1" smd circle
			(at -0.40005 0 270)
			(size 0 0)
			(layers "F.Cu" "F.Mask" "F.Paste")
			(net "PVCCIN_CPU1")
		)
		(pad "2" smd circle
			(at 0.40005 0 270)
			(size 0 0)
			(layers "F.Cu" "F.Mask" "F.Paste")
			(net "GND")
		)
	)
	(footprint ""
		(layer "F.Cu")
		(at 20.785582 -428.024036 90)
		(property "Reference" "R3440"
			(at 0 0 90)
			(layer "F.SilkS")
			(hide yes)
			(effects
				(font
					(size 1.27 1.27)
				)
			)
		)
		(property "Value" ""
			(at 0 0 90)
			(layer "F.Fab")
			(effects
				(font
					(size 1.27 1.27)
				)
			)
		)
		(duplicate_pad_numbers_are_jumpers no)
		(fp_line
			(start 0.7874 -0.4064)
			(end 0.7874 0.4064)
			(stroke
				(width 0.1524)
				(type default)
			)
			(layer "F.SilkS")
		)
		(fp_line
			(start -0.7874 -0.4064)
			(end 0.7874 -0.4064)
			(stroke
				(width 0.1524)
				(type default)
			)
			(layer "F.SilkS")
		)
		(fp_line
			(start 0.7874 0.4064)
			(end -0.7874 0.4064)
			(stroke
				(width 0.1524)
				(type default)
			)
			(layer "F.SilkS")
		)
		(fp_line
			(start -0.7874 0.4064)
			(end -0.7874 -0.4064)
			(stroke
				(width 0.1524)
				(type default)
			)
			(layer "F.SilkS")
		)
		(fp_line
			(start -0.12065 -0.305054)
			(end -0.12065 -0.2794)
			(stroke
				(width 0.1)
				(type default)
			)
			(layer "F.Fab")
		)
		(fp_line
			(start -0.67945 -0.305054)
			(end -0.12065 -0.305054)
			(stroke
				(width 0.1)
				(type default)
			)
			(layer "F.Fab")
		)
		(fp_line
			(start 0.67945 -0.3048)
			(end 0.67945 0.3048)
			(stroke
				(width 0.1)
				(type default)
			)
			(layer "F.Fab")
		)
		(fp_line
			(start 0.12065 -0.3048)
			(end 0.67945 -0.3048)
			(stroke
				(width 0.1)
				(type default)
			)
			(layer "F.Fab")
		)
		(fp_line
			(start 0.12065 -0.2794)
			(end 0.12065 -0.3048)
			(stroke
				(width 0.1)
				(type default)
			)
			(layer "F.Fab")
		)
		(fp_line
			(start -0.12065 -0.2794)
			(end 0.12065 -0.2794)
			(stroke
				(width 0.1)
				(type default)
			)
			(layer "F.Fab")
		)
		(fp_line
			(start 0.120396 0.2794)
			(end -0.12065 0.2794)
			(stroke
				(width 0.1)
				(type default)
			)
			(layer "F.Fab")
		)
		(fp_line
			(start -0.12065 0.2794)
			(end -0.12065 0.3048)
			(stroke
				(width 0.1)
				(type default)
			)
			(layer "F.Fab")
		)
		(fp_line
			(start 0.67945 0.3048)
			(end 0.120396 0.3048)
			(stroke
				(width 0.1)
				(type default)
			)
			(layer "F.Fab")
		)
		(fp_line
			(start 0.120396 0.3048)
			(end 0.120396 0.2794)
			(stroke
				(width 0.1)
				(type default)
			)
			(layer "F.Fab")
		)
		(fp_line
			(start -0.12065 0.3048)
			(end -0.67945 0.3048)
			(stroke
				(width 0.1)
				(type default)
			)
			(layer "F.Fab")
		)
		(fp_line
			(start -0.67945 0.3048)
			(end -0.67945 -0.305054)
			(stroke
				(width 0.1)
				(type default)
			)
			(layer "F.Fab")
		)
		(pad "1" smd circle
			(at -0.40005 0 90)
			(size 0 0)
			(layers "F.Cu" "F.Mask" "F.Paste")
			(net "GPU_BASE_ID0")
		)
		(pad "2" smd circle
			(at 0.40005 0 90)
			(size 0 0)
			(layers "F.Cu" "F.Mask" "F.Paste")
			(net "GND")
		)
	)
)
